# SCM (Grand Teton) — schematic netlist excerpt (pin names and nets, part order shuffled) for the footprints in the layout excerpt that follows; sources: Cadence DE-HDL packaged netlist, KiCad conversion of 12092022_DA0F0TMDCD0_F0T_Management_Board_D_brd_V3_OCP.brd

C177  Q_CAP  47UF 6.3V 20% X6S  pkg C1206  page 29 : A = P5V_USB_REAR ; B = GND
R202  Q_RES  10K 1% EMPTY  pkg 0402LF  page 32 : A = GND ; B = JTAG_SCM_TCK
R285  Q_RES  4.7K 1% CHIP  pkg 0402LF  page 32 : A = JTAG_SCM_PLD_TCK ; B = GND
H3  HOLE  EMPTY  pkg TH  page 57 : \1\ = GND

(kicad_pcb
	(version 20260206)
	(generator "pcbnew")
	(generator_version "10.0")
	(general
		(thickness 1.6)
		(legacy_teardrops no)
	)
	(paper "A4")
	(title_block
		(title "12092022_DA0F0TMDCD0_F0T_Management_Board_D_brd_V3_OCP.brd")
		(comment 1 "Grand Teton / footprints 33-36 of 1440")
	)
	(layers
		(0 "F.Cu" signal "TOP")
		(4 "In1.Cu" signal "GND")
		(6 "In2.Cu" signal "IN1")
		(8 "In3.Cu" signal "GND1")
		(10 "In4.Cu" signal "IN2")
		(12 "In5.Cu" signal "VCC")
		(14 "In6.Cu" signal "VCC1")
		(16 "In7.Cu" signal "IN3")
		(18 "In8.Cu" signal "GND2")
		(20 "In9.Cu" signal "IN4")
		(22 "In10.Cu" signal "GND3")
		(2 "B.Cu" signal "BOTTOM")
		(9 "F.Adhes" user "F.Adhesive")
		(11 "B.Adhes" user "B.Adhesive")
		(13 "F.Paste" user "Package Geometry/Pastemask Top")
		(15 "B.Paste" user "Package Geometry/Pastemask Bottom")
		(5 "F.SilkS" user "Ref Des/Silkscreen Top")
		(7 "B.SilkS" user "Ref Des/Silkscreen Bottom")
		(1 "F.Mask" user "Board Geometry/Soldermask Top")
		(3 "B.Mask" user "Board Geometry/Soldermask Bottom")
		(17 "Dwgs.User" user "User.Drawings")
		(19 "Cmts.User" user "User.Comments")
		(21 "Eco1.User" user "User.Eco1")
		(23 "Eco2.User" user "User.Eco2")
		(25 "Edge.Cuts" user "Board Geometry/Outline")
		(27 "Margin" user)
		(31 "F.CrtYd" user "Package Geometry/Place Bound Top")
		(29 "B.CrtYd" user "Package Geometry/Place Bound Bottom")
		(35 "F.Fab" user "Ref Des/Assembly Top")
		(33 "B.Fab" user "Ref Des/Assembly Bottom")
	)
	(footprint ""
		(layer "F.Cu")
		(at 10.287 -92.837 90)
		(property "Reference" "R285"
			(at 0 0 90)
			(layer "F.SilkS")
			(hide yes)
			(effects
				(font
					(size 1.27 1.27)
				)
			)
		)
		(property "Value" ""
			(at 0 0 90)
			(layer "F.Fab")
			(effects
				(font
					(size 1.27 1.27)
				)
			)
		)
		(duplicate_pad_numbers_are_jumpers no)
		(fp_line
			(start 0.7874 -0.4064)
			(end 0.7874 0.4064)
			(stroke
				(width 0.1524)
				(type default)
			)
			(layer "F.SilkS")
		)
		(fp_line
			(start -0.7874 -0.4064)
			(end 0.7874 -0.4064)
			(stroke
				(width 0.1524)
				(type default)
			)
			(layer "F.SilkS")
		)
		(fp_line
			(start 0.7874 0.4064)
			(end -0.7874 0.4064)
			(stroke
				(width 0.1524)
				(type default)
			)
			(layer "F.SilkS")
		)
		(fp_line
			(start -0.7874 0.4064)
			(end -0.7874 -0.4064)
			(stroke
				(width 0.1524)
				(type default)
			)
			(layer "F.SilkS")
		)
		(fp_line
			(start -0.12065 -0.305054)
			(end -0.12065 -0.2794)
			(stroke
				(width 0.1)
				(type default)
			)
			(layer "F.Fab")
		)
		(fp_line
			(start -0.67945 -0.305054)
			(end -0.12065 -0.305054)
			(stroke
				(width 0.1)
				(type default)
			)
			(layer "F.Fab")
		)
		(fp_line
			(start 0.67945 -0.3048)
			(end 0.67945 0.3048)
			(stroke
				(width 0.1)
				(type default)
			)
			(layer "F.Fab")
		)
		(fp_line
			(start 0.12065 -0.3048)
			(end 0.67945 -0.3048)
			(stroke
				(width 0.1)
				(type default)
			)
			(layer "F.Fab")
		)
		(fp_line
			(start 0.12065 -0.2794)
			(end 0.12065 -0.3048)
			(stroke
				(width 0.1)
				(type default)
			)
			(layer "F.Fab")
		)
		(fp_line
			(start -0.12065 -0.2794)
			(end 0.12065 -0.2794)
			(stroke
				(width 0.1)
				(type default)
			)
			(layer "F.Fab")
		)
		(fp_line
			(start 0.120396 0.2794)
			(end -0.12065 0.2794)
			(stroke
				(width 0.1)
				(type default)
			)
			(layer "F.Fab")
		)
		(fp_line
			(start -0.12065 0.2794)
			(end -0.12065 0.3048)
			(stroke
				(width 0.1)
				(type default)
			)
			(layer "F.Fab")
		)
		(fp_line
			(start 0.67945 0.3048)
			(end 0.120396 0.3048)
			(stroke
				(width 0.1)
				(type default)
			)
			(layer "F.Fab")
		)
		(fp_line
			(start 0.120396 0.3048)
			(end 0.120396 0.2794)
			(stroke
				(width 0.1)
				(type default)
			)
			(layer "F.Fab")
		)
		(fp_line
			(start -0.12065 0.3048)
			(end -0.67945 0.3048)
			(stroke
				(width 0.1)
				(type default)
			)
			(layer "F.Fab")
		)
		(fp_line
			(start -0.67945 0.3048)
			(end -0.67945 -0.305054)
			(stroke
				(width 0.1)
				(type default)
			)
			(layer "F.Fab")
		)
		(pad "1" smd circle
			(at -0.40005 0 90)
			(size 0 0)
			(layers "F.Cu" "F.Mask" "F.Paste")
			(net "JTAG_SCM_PLD_TCK")
		)
		(pad "2" smd circle
			(at 0.40005 0 90)
			(size 0 0)
			(layers "F.Cu" "F.Mask" "F.Paste")
			(net "GND")
		)
	)
	(footprint ""
		(layer "F.Cu")
		(at 61.5188 -30.861 90)
		(property "Reference" "R202"
			(at 0 0 90)
			(layer "F.SilkS")
			(hide yes)
			(effects
				(font
					(size 1.27 1.27)
				)
			)
		)
		(property "Value" ""
			(at 0 0 90)
			(layer "F.Fab")
			(effects
				(font
					(size 1.27 1.27)
				)
			)
		)
		(duplicate_pad_numbers_are_jumpers no)
		(fp_line
			(start 0.7874 -0.4064)
			(end 0.7874 0.4064)
			(stroke
				(width 0.1524)
				(type default)
			)
			(layer "F.SilkS")
		)
		(fp_line
			(start -0.7874 -0.4064)
			(end 0.7874 -0.4064)
			(stroke
				(width 0.1524)
				(type default)
			)
			(layer "F.SilkS")
		)
		(fp_line
			(start 0.7874 0.4064)
			(end -0.7874 0.4064)
			(stroke
				(width 0.1524)
				(type default)
			)
			(layer "F.SilkS")
		)
		(fp_line
			(start -0.7874 0.4064)
			(end -0.7874 -0.4064)
			(stroke
				(width 0.1524)
				(type default)
			)
			(layer "F.SilkS")
		)
		(fp_line
			(start -0.12065 -0.305054)
			(end -0.12065 -0.2794)
			(stroke
				(width 0.1)
				(type default)
			)
			(layer "F.Fab")
		)
		(fp_line
			(start -0.67945 -0.305054)
			(end -0.12065 -0.305054)
			(stroke
				(width 0.1)
				(type default)
			)
			(layer "F.Fab")
		)
		(fp_line
			(start 0.67945 -0.3048)
			(end 0.67945 0.3048)
			(stroke
				(width 0.1)
				(type default)
			)
			(layer "F.Fab")
		)
		(fp_line
			(start 0.12065 -0.3048)
			(end 0.67945 -0.3048)
			(stroke
				(width 0.1)
				(type default)
			)
			(layer "F.Fab")
		)
		(fp_line
			(start 0.12065 -0.2794)
			(end 0.12065 -0.3048)
			(stroke
				(width 0.1)
				(type default)
			)
			(layer "F.Fab")
		)
		(fp_line
			(start -0.12065 -0.2794)
			(end 0.12065 -0.2794)
			(stroke
				(width 0.1)
				(type default)
			)
			(layer "F.Fab")
		)
		(fp_line
			(start 0.120396 0.2794)
			(end -0.12065 0.2794)
			(stroke
				(width 0.1)
				(type default)
			)
			(layer "F.Fab")
		)
		(fp_line
			(start -0.12065 0.2794)
			(end -0.12065 0.3048)
			(stroke
				(width 0.1)
				(type default)
			)
			(layer "F.Fab")
		)
		(fp_line
			(start 0.67945 0.3048)
			(end 0.120396 0.3048)
			(stroke
				(width 0.1)
				(type default)
			)
			(layer "F.Fab")
		)
		(fp_line
			(start 0.120396 0.3048)
			(end 0.120396 0.2794)
			(stroke
				(width 0.1)
				(type default)
			)
			(layer "F.Fab")
		)
		(fp_line
			(start -0.12065 0.3048)
			(end -0.67945 0.3048)
			(stroke
				(width 0.1)
				(type default)
			)
			(layer "F.Fab")
		)
		(fp_line
			(start -0.67945 0.3048)
			(end -0.67945 -0.305054)
			(stroke
				(width 0.1)
				(type default)
			)
			(layer "F.Fab")
		)
		(pad "1" smd circle
			(at -0.40005 0 90)
			(size 0 0)
			(layers "F.Cu" "F.Mask" "F.Paste")
			(net "GND")
		)
		(pad "2" smd circle
			(at 0.40005 0 90)
			(size 0 0)
			(layers "F.Cu" "F.Mask" "F.Paste")
			(net "JTAG_SCM_TCK")
		)
	)
	(footprint ""
		(layer "F.Cu")
		(at 51.562 -20.32)
		(property "Reference" "C177"
			(at 0 0 0)
			(layer "F.SilkS")
			(hide yes)
			(effects
				(font
					(size 1.27 1.27)
				)
			)
		)
		(property "Value" ""
			(at 0 0 0)
			(layer "F.Fab")
			(effects
				(font
					(size 1.27 1.27)
				)
			)
		)
		(duplicate_pad_numbers_are_jumpers no)
		(fp_line
			(start -2.2098 -0.9398)
			(end 2.2098 -0.9398)
			(stroke
				(width 0.1524)
				(type default)
			)
			(layer "F.SilkS")
		)
		(fp_line
			(start -2.2098 0.9398)
			(end -2.2098 -0.9398)
			(stroke
				(width 0.1524)
				(type default)
			)
			(layer "F.SilkS")
		)
		(fp_line
			(start 2.2098 -0.9398)
			(end 2.2098 0.9398)
			(stroke
				(width 0.1524)
				(type default)
			)
			(layer "F.SilkS")
		)
		(fp_line
			(start 2.2098 0.9398)
			(end -2.2098 0.9398)
			(stroke
				(width 0.1524)
				(type default)
			)
			(layer "F.SilkS")
		)
		(fp_line
			(start -1.700022 -0.899922)
			(end 1.700022 -0.899922)
			(stroke
				(width 0.1)
				(type default)
			)
			(layer "F.Fab")
		)
		(fp_line
			(start -1.700022 0.899922)
			(end -1.700022 -0.899922)
			(stroke
				(width 0.1)
				(type default)
			)
			(layer "F.Fab")
		)
		(fp_line
			(start 1.700022 -0.899922)
			(end 1.700022 0.899922)
			(stroke
				(width 0.1)
				(type default)
			)
			(layer "F.Fab")
		)
		(fp_line
			(start 1.700022 0.899922)
			(end -1.700022 0.899922)
			(stroke
				(width 0.1)
				(type default)
			)
			(layer "F.Fab")
		)
		(pad "1" smd rect
			(at -1.4732 0 180)
			(size 1.1684 1.5748)
			(layers "F.Cu" "F.Mask" "F.Paste")
			(net "P5V_USB_REAR")
		)
		(pad "2" smd rect
			(at 1.4732 0 180)
			(size 1.1684 1.5748)
			(layers "F.Cu" "F.Mask" "F.Paste")
			(net "GND")
		)
	)
	(footprint ""
		(layer "F.Cu")
		(at 76.499974 -107.700064)
		(property "Reference" "H3"
			(at 1.279652 -3.484118 0)
			(unlocked yes)
			(layer "F.SilkS")
			(effects
				(font
					(size 0.7874 0.5842)
					(thickness 0.1524)
				)
				(justify left)
			)
		)
		(property "Value" ""
			(at 0 0 0)
			(layer "F.Fab")
			(effects
				(font
					(size 1.27 1.27)
				)
			)
		)
		(duplicate_pad_numbers_are_jumpers no)
		(pad "1" thru_hole circle
			(at 0 0)
			(size 6.0198 6.0198)
			(drill 3.4036)
			(layers "*.Cu" "*.Mask")
			(remove_unused_layers no)
			(net "GND")
			(clearance -1.0541)
		)
	)
)
